# BASEBOARD_FAB2 (Tioga Pass) — schematic netlist excerpt (pin names and nets, part order shuffled) for the footprints in the layout excerpt that follows; sources: Cadence DE-HDL packaged netlist, KiCad conversion of Wiwynn_Tioga_Pass_MB.brd

C6M3  CAP  10UF 16V 10% X6S  pkg 0805  page 234 : A = VR_FET_SW_P12V_STBY_PVPP_KLM ; B = GND
R9P3  RES  33.2 1% CHIP  pkg 0402  page 206 : A = IRQ_PVCCIN_CPU1_VRHOT_LVC3_R_N ; B = IRQ_PVCCIN_CPU1_VRHOT_LVC3_N
R2L23  RES  2.0K 1% CHIP  pkg 0402  page 173 : A = P3V3 ; B = PU_DATAIN1_SATA_1_R

(kicad_pcb
	(version 20260206)
	(generator "pcbnew")
	(generator_version "10.0")
	(general
		(thickness 1.6)
		(legacy_teardrops no)
	)
	(paper "A4")
	(title_block
		(title "Wiwynn_Tioga_Pass_MB.brd")
		(comment 1 "Tioga Pass / footprints 2733-2735 of 4770")
	)
	(layers
		(0 "F.Cu" signal "TOP")
		(4 "In1.Cu" signal "L2GND")
		(6 "In2.Cu" signal "L3")
		(8 "In3.Cu" signal "L4GND")
		(10 "In4.Cu" signal "L5")
		(12 "In5.Cu" signal "L6GND")
		(14 "In6.Cu" signal "L7VCC")
		(16 "In7.Cu" signal "L8VCC")
		(18 "In8.Cu" signal "L9GND")
		(20 "In9.Cu" signal "L10")
		(22 "In10.Cu" signal "L11GND")
		(24 "In11.Cu" signal "L12")
		(26 "In12.Cu" signal "L13GND")
		(2 "B.Cu" signal "BOTTOM")
		(9 "F.Adhes" user "F.Adhesive")
		(11 "B.Adhes" user "B.Adhesive")
		(13 "F.Paste" user "Package Geometry/Pastemask Top")
		(15 "B.Paste" user "Package Geometry/Pastemask Bottom")
		(5 "F.SilkS" user "Ref Des/Silkscreen Top")
		(7 "B.SilkS" user "Ref Des/Silkscreen Bottom")
		(1 "F.Mask" user "Board Geometry/Soldermask Top")
		(3 "B.Mask" user "Board Geometry/Soldermask Bottom")
		(17 "Dwgs.User" user "User.Drawings")
		(19 "Cmts.User" user "User.Comments")
		(21 "Eco1.User" user "User.Eco1")
		(23 "Eco2.User" user "User.Eco2")
		(25 "Edge.Cuts" user "Board Geometry/Outline")
		(27 "Margin" user)
		(31 "F.CrtYd" user "Package Geometry/Place Bound Top")
		(29 "B.CrtYd" user "Package Geometry/Place Bound Bottom")
		(35 "F.Fab" user "Ref Des/Assembly Top")
		(33 "B.Fab" user "Ref Des/Assembly Bottom")
	)
	(footprint ""
		(layer "B.Cu")
		(at 417.895024 -140.843 180)
		(property "Reference" "R2L23"
			(at 0 0 0)
			(layer "B.SilkS")
			(hide yes)
			(effects
				(font
					(size 1.27 1.27)
				)
				(justify mirror)
			)
		)
		(property "Value" ""
			(at 0 0 0)
			(layer "B.Fab")
			(effects
				(font
					(size 1.27 1.27)
				)
				(justify mirror)
			)
		)
		(duplicate_pad_numbers_are_jumpers no)
		(fp_poly
			(pts
				(xy 0.2794 -0.1016) (xy -0.2794 -0.1016) (xy -0.2794 0.9906) (xy 0.2794 0.9906)
			)
			(stroke
				(width 0)
				(type default)
			)
			(fill no)
			(layer "B.CrtYd")
		)
		(fp_line
			(start 0.2794 0.9906)
			(end -0.2794 0.9906)
			(stroke
				(width 0.1)
				(type default)
			)
			(layer "B.Fab")
		)
		(fp_line
			(start 0.2794 -0.1016)
			(end 0.2794 0.9906)
			(stroke
				(width 0.1)
				(type default)
			)
			(layer "B.Fab")
		)
		(fp_line
			(start -0.2794 0.9906)
			(end -0.2794 -0.1016)
			(stroke
				(width 0.1)
				(type default)
			)
			(layer "B.Fab")
		)
		(fp_line
			(start -0.2794 -0.1016)
			(end 0.2794 -0.1016)
			(stroke
				(width 0.1)
				(type default)
			)
			(layer "B.Fab")
		)
		(pad "1" smd rect
			(at 0 0)
			(size 0.508 0.508)
			(layers "B.Cu" "B.Mask" "B.Paste")
			(net "P3V3")
		)
		(pad "2" smd rect
			(at 0 0.889)
			(size 0.508 0.508)
			(layers "B.Cu" "B.Mask" "B.Paste")
			(net "PU_DATAIN1_SATA_1_R")
		)
		(zone
			(layer "B.Cu")
			(hatch none 0.5)
			(connect_pads
				(clearance 0)
			)
			(min_thickness 0.25)
			(keepout
				(tracks not_allowed)
				(vias allowed)
				(pads allowed)
				(copperpour not_allowed)
				(footprints allowed)
			)
			(placement
				(enabled no)
				(sheetname "")
			)
			(fill
				(thermal_gap 0.5)
				(thermal_bridge_width 0.5)
				(island_removal_mode 0)
			)
			(polygon
				(pts
					(xy 417.641024 -141.478) (xy 418.149024 -141.478) (xy 418.149024 -141.097) (xy 417.641024 -141.097)
				)
			)
		)
		(zone
			(layer "B.Cu")
			(hatch none 0.5)
			(connect_pads
				(clearance 0)
			)
			(min_thickness 0.25)
			(keepout
				(tracks allowed)
				(vias not_allowed)
				(pads allowed)
				(copperpour not_allowed)
				(footprints allowed)
			)
			(placement
				(enabled no)
				(sheetname "")
			)
			(fill
				(thermal_gap 0.5)
				(thermal_bridge_width 0.5)
				(island_removal_mode 0)
			)
			(polygon
				(pts
					(xy 417.641024 -141.097) (xy 418.149024 -141.097) (xy 418.149024 -141.478) (xy 417.641024 -141.478)
				)
			)
		)
	)
	(footprint ""
		(layer "B.Cu")
		(at 14.478 -87.63)
		(property "Reference" "R9P3"
			(at 0 0 0)
			(layer "B.SilkS")
			(hide yes)
			(effects
				(font
					(size 1.27 1.27)
				)
				(justify mirror)
			)
		)
		(property "Value" ""
			(at 0 0 0)
			(layer "B.Fab")
			(effects
				(font
					(size 1.27 1.27)
				)
				(justify mirror)
			)
		)
		(duplicate_pad_numbers_are_jumpers no)
		(fp_poly
			(pts
				(xy 0.2794 -0.1016) (xy -0.2794 -0.1016) (xy -0.2794 0.9906) (xy 0.2794 0.9906)
			)
			(stroke
				(width 0)
				(type default)
			)
			(fill no)
			(layer "B.CrtYd")
		)
		(fp_line
			(start -0.2794 -0.1016)
			(end 0.2794 -0.1016)
			(stroke
				(width 0.1)
				(type default)
			)
			(layer "B.Fab")
		)
		(fp_line
			(start -0.2794 0.9906)
			(end -0.2794 -0.1016)
			(stroke
				(width 0.1)
				(type default)
			)
			(layer "B.Fab")
		)
		(fp_line
			(start 0.2794 -0.1016)
			(end 0.2794 0.9906)
			(stroke
				(width 0.1)
				(type default)
			)
			(layer "B.Fab")
		)
		(fp_line
			(start 0.2794 0.9906)
			(end -0.2794 0.9906)
			(stroke
				(width 0.1)
				(type default)
			)
			(layer "B.Fab")
		)
		(pad "1" smd rect
			(at 0 0 180)
			(size 0.508 0.508)
			(layers "B.Cu" "B.Mask" "B.Paste")
			(net "IRQ_PVCCIN_CPU1_VRHOT_LVC3_R_N")
		)
		(pad "2" smd rect
			(at 0 0.889 180)
			(size 0.508 0.508)
			(layers "B.Cu" "B.Mask" "B.Paste")
			(net "IRQ_PVCCIN_CPU1_VRHOT_LVC3_N")
		)
		(zone
			(layer "B.Cu")
			(hatch none 0.5)
			(connect_pads
				(clearance 0)
			)
			(min_thickness 0.25)
			(keepout
				(tracks allowed)
				(vias not_allowed)
				(pads allowed)
				(copperpour not_allowed)
				(footprints allowed)
			)
			(placement
				(enabled no)
				(sheetname "")
			)
			(fill
				(thermal_gap 0.5)
				(thermal_bridge_width 0.5)
				(island_removal_mode 0)
			)
			(polygon
				(pts
					(xy 14.732 -87.376) (xy 14.224 -87.376) (xy 14.224 -86.995) (xy 14.732 -86.995)
				)
			)
		)
		(zone
			(layer "B.Cu")
			(hatch none 0.5)
			(connect_pads
				(clearance 0)
			)
			(min_thickness 0.25)
			(keepout
				(tracks not_allowed)
				(vias allowed)
				(pads allowed)
				(copperpour not_allowed)
				(footprints allowed)
			)
			(placement
				(enabled no)
				(sheetname "")
			)
			(fill
				(thermal_gap 0.5)
				(thermal_bridge_width 0.5)
				(island_removal_mode 0)
			)
			(polygon
				(pts
					(xy 14.732 -86.995) (xy 14.224 -86.995) (xy 14.224 -87.376) (xy 14.732 -87.376)
				)
			)
		)
	)
	(footprint ""
		(layer "B.Cu")
		(at 183.3626 -134.5438 90)
		(property "Reference" "C6M3"
			(at -1.47828 0.78994 180)
			(unlocked yes)
			(layer "B.SilkS")
			(effects
				(font
					(size 0.4064 0.254)
					(thickness 0.1524)
				)
				(justify mirror)
			)
		)
		(property "Value" ""
			(at 0 0 90)
			(layer "B.Fab")
			(effects
				(font
					(size 1.27 1.27)
				)
				(justify mirror)
			)
		)
		(duplicate_pad_numbers_are_jumpers no)
		(fp_poly
			(pts
				(xy 0.7239 -0.2159) (xy -0.7239 -0.2159) (xy -0.7239 1.9939) (xy 0.7239 1.9939)
			)
			(stroke
				(width 0)
				(type default)
			)
			(fill no)
			(layer "B.CrtYd")
		)
		(fp_line
			(start 0.7239 -0.2159)
			(end 0.7239 1.9939)
			(stroke
				(width 0.1)
				(type default)
			)
			(layer "B.Fab")
		)
		(fp_line
			(start -0.7239 -0.2159)
			(end 0.7239 -0.2159)
			(stroke
				(width 0.1)
				(type default)
			)
			(layer "B.Fab")
		)
		(fp_line
			(start 0.7239 1.9939)
			(end -0.7239 1.9939)
			(stroke
				(width 0.1)
				(type default)
			)
			(layer "B.Fab")
		)
		(fp_line
			(start -0.7239 1.9939)
			(end -0.7239 -0.2159)
			(stroke
				(width 0.1)
				(type default)
			)
			(layer "B.Fab")
		)
		(pad "1" smd rect
			(at 0 0 270)
			(size 1.27 1.016)
			(layers "B.Cu" "B.Mask" "B.Paste")
			(net "VR_FET_SW_P12V_STBY_PVPP_KLM")
		)
		(pad "2" smd rect
			(at 0 1.778 270)
			(size 1.27 1.016)
			(layers "B.Cu" "B.Mask" "B.Paste")
			(net "GND")
		)
		(zone
			(layer "B.Cu")
			(hatch none 0.5)
			(connect_pads
				(clearance 0)
			)
			(min_thickness 0.25)
			(keepout
				(tracks not_allowed)
				(vias allowed)
				(pads allowed)
				(copperpour not_allowed)
				(footprints allowed)
			)
			(placement
				(enabled no)
				(sheetname "")
			)
			(fill
				(thermal_gap 0.5)
				(thermal_bridge_width 0.5)
				(island_removal_mode 0)
			)
			(polygon
				(pts
					(xy 183.8706 -135.1788) (xy 183.8706 -133.9088) (xy 184.6326 -133.9088) (xy 184.6326 -135.1788)
				)
			)
		)
	)
)
